# TIMECARD (Time Appliance Project (Time Card)) — schematic netlist excerpt (pin names and nets, part order shuffled) for the footprints in the layout excerpt that follows; sources: Cadence DE-HDL packaged netlist, KiCad conversion of R4006-B0001-02_R01.brd

R498  RESISTOR  1MOHM 1%  pkg SMC_0402R_H016  page 23 : \1\ = SG ; \2\ = BF_SMA1_SIG_IO_CONN
R359  RESISTOR  10KOHM 1%  pkg SMC_0402R_H016  page 13 : \1\ = MHZ200CLKP_CLKIN ; \2\ = SG

(kicad_pcb
	(version 20260206)
	(generator "pcbnew")
	(generator_version "10.0")
	(general
		(thickness 1.6)
		(legacy_teardrops no)
	)
	(paper "A4")
	(title_block
		(title "timecard-production-celestica-r4006 — R4006-B0001-02_R01.brd")
		(comment 1 "Time Appliance Project (Time Card) / footprints 6-7 of 1113")
	)
	(layers
		(0 "F.Cu" signal "TOP")
		(4 "In1.Cu" signal "L02_GND1")
		(6 "In2.Cu" signal "L03_SIG1")
		(8 "In3.Cu" signal "L04_GND2")
		(10 "In4.Cu" signal "L05_VCC1")
		(12 "In5.Cu" signal "L06_VCC2")
		(14 "In6.Cu" signal "L07_GND3")
		(16 "In7.Cu" signal "L08_SIG2")
		(18 "In8.Cu" signal "L09_GND4")
		(2 "B.Cu" signal "BOTTOM")
		(9 "F.Adhes" user "F.Adhesive")
		(11 "B.Adhes" user "B.Adhesive")
		(13 "F.Paste" user "Package Geometry/Pastemask Top")
		(15 "B.Paste" user "Package Geometry/Pastemask Bottom")
		(5 "F.SilkS" user "Ref Des/Silkscreen Top")
		(7 "B.SilkS" user "Ref Des/Silkscreen Bottom")
		(1 "F.Mask" user "Board Geometry/Soldermask Top")
		(3 "B.Mask" user "Board Geometry/Soldermask Bottom")
		(17 "Dwgs.User" user "User.Drawings")
		(19 "Cmts.User" user "User.Comments")
		(21 "Eco1.User" user "User.Eco1")
		(23 "Eco2.User" user "User.Eco2")
		(25 "Edge.Cuts" user "Board Geometry/Outline")
		(27 "Margin" user)
		(31 "F.CrtYd" user "Package Geometry/Place Bound Top")
		(29 "B.CrtYd" user "Package Geometry/Place Bound Bottom")
		(35 "F.Fab" user "Ref Des/Assembly Top")
		(33 "B.Fab" user "Ref Des/Assembly Bottom")
	)
	(footprint ""
		(layer "F.Cu")
		(at 112.7125 -28.5242)
		(property "Reference" "R359"
			(at 2.00787 2.1082 90)
			(unlocked yes)
			(layer "F.SilkS")
			(effects
				(font
					(size 0.7874 0.5842)
					(thickness 0.1524)
				)
			)
		)
		(property "Value" "VAL*"
			(at 0.02032 2.13233 0)
			(unlocked yes)
			(layer "F.Fab")
			(hide yes)
			(effects
				(font
					(size 0.7874 0.5842)
					(thickness 0.1524)
				)
			)
		)
		(property "Tolerance" "TOL*"
			(at 0.044704 3.05435 0)
			(unlocked yes)
			(layer "Cmts.User")
			(hide yes)
			(effects
				(font
					(size 0.7874 0.5842)
					(thickness 0.1524)
				)
			)
		)
		(property "User Part Number" "PARTNUM*"
			(at 0.02032 4.024884 0)
			(unlocked yes)
			(layer "Cmts.User")
			(hide yes)
			(effects
				(font
					(size 0.7874 0.5842)
					(thickness 0.1524)
				)
			)
		)
		(property "Device Type" "RESISTOR-G155-11002-01,10KOHM,A"
			(at 0.008382 1.210564 0)
			(unlocked yes)
			(layer "F.Fab")
			(hide yes)
			(effects
				(font
					(size 0.7874 0.5842)
					(thickness 0.1524)
				)
			)
		)
		(duplicate_pad_numbers_are_jumpers no)
		(fp_line
			(start -1.143 -0.5588)
			(end -1.143 0.5588)
			(stroke
				(width 0.1)
				(type default)
			)
			(layer "F.SilkS")
		)
		(fp_line
			(start -1.143 0.5588)
			(end 1.143 0.5588)
			(stroke
				(width 0.1)
				(type default)
			)
			(layer "F.SilkS")
		)
		(fp_line
			(start 1.143 -0.5588)
			(end -1.143 -0.5588)
			(stroke
				(width 0.1)
				(type default)
			)
			(layer "F.SilkS")
		)
		(fp_line
			(start 1.143 0.5588)
			(end 1.143 -0.5588)
			(stroke
				(width 0.1)
				(type default)
			)
			(layer "F.SilkS")
		)
		(fp_poly
			(pts
				(xy -1.143 0.5588) (xy 1.143 0.5588) (xy 1.143 -0.5588) (xy -1.143 -0.5588)
			)
			(stroke
				(width 0)
				(type default)
			)
			(fill no)
			(layer "F.CrtYd")
		)
		(fp_line
			(start -0.508 -0.3048)
			(end -0.508 0.3048)
			(stroke
				(width 0.1)
				(type default)
			)
			(layer "F.Fab")
		)
		(fp_line
			(start -0.508 0.3048)
			(end 0.508 0.3048)
			(stroke
				(width 0.1)
				(type default)
			)
			(layer "F.Fab")
		)
		(fp_line
			(start 0.508 -0.3048)
			(end -0.508 -0.3048)
			(stroke
				(width 0.1)
				(type default)
			)
			(layer "F.Fab")
		)
		(fp_line
			(start 0.508 0.3048)
			(end 0.508 -0.3048)
			(stroke
				(width 0.1)
				(type default)
			)
			(layer "F.Fab")
		)
		(pad "1" smd rect
			(at -0.5334 0)
			(size 0.7112 0.6096)
			(layers "F.Cu" "F.Mask" "F.Paste")
			(net "MHZ200CLKP_CLKIN")
		)
		(pad "2" smd rect
			(at 0.5334 0)
			(size 0.7112 0.6096)
			(layers "F.Cu" "F.Mask" "F.Paste")
			(net "SG")
		)
		(zone
			(layer "F.Cu")
			(hatch none 0.5)
			(connect_pads
				(clearance 0)
			)
			(min_thickness 0.25)
			(keepout
				(tracks allowed)
				(vias not_allowed)
				(pads allowed)
				(copperpour not_allowed)
				(footprints allowed)
			)
			(placement
				(enabled no)
				(sheetname "")
			)
			(fill
				(thermal_gap 0.5)
				(thermal_bridge_width 0.5)
				(island_removal_mode 0)
			)
			(polygon
				(pts
					(xy 112.6363 -28.2194) (xy 112.7887 -28.2194) (xy 112.7887 -28.829) (xy 112.6363 -28.829)
				)
			)
		)
		(zone
			(layer "F.Cu")
			(hatch none 0.5)
			(connect_pads
				(clearance 0)
			)
			(min_thickness 0.25)
			(keepout
				(tracks not_allowed)
				(vias allowed)
				(pads allowed)
				(copperpour not_allowed)
				(footprints allowed)
			)
			(placement
				(enabled no)
				(sheetname "")
			)
			(fill
				(thermal_gap 0.5)
				(thermal_bridge_width 0.5)
				(island_removal_mode 0)
			)
			(polygon
				(pts
					(xy 112.6363 -28.2194) (xy 112.7887 -28.2194) (xy 112.7887 -28.829) (xy 112.6363 -28.829)
				)
			)
		)
	)
	(footprint ""
		(layer "F.Cu")
		(at 11.4808 -59.6138 -90)
		(property "Reference" "R498"
			(at -0.5842 1.40843 90)
			(unlocked yes)
			(layer "F.SilkS")
			(effects
				(font
					(size 0.7874 0.5842)
					(thickness 0.1524)
				)
			)
		)
		(property "Value" "VAL*"
			(at 0.02032 2.13233 270)
			(unlocked yes)
			(layer "F.Fab")
			(hide yes)
			(effects
				(font
					(size 0.7874 0.5842)
					(thickness 0.1524)
				)
			)
		)
		(property "Tolerance" "TOL*"
			(at 0.044704 3.05435 270)
			(unlocked yes)
			(layer "Cmts.User")
			(hide yes)
			(effects
				(font
					(size 0.7874 0.5842)
					(thickness 0.1524)
				)
			)
		)
		(property "User Part Number" "PARTNUM*"
			(at 0.02032 4.024884 270)
			(unlocked yes)
			(layer "Cmts.User")
			(hide yes)
			(effects
				(font
					(size 0.7874 0.5842)
					(thickness 0.1524)
				)
			)
		)
		(property "Device Type" "RESISTOR-G155-11004-01,1MOHM,1%"
			(at 0.008382 1.210564 270)
			(unlocked yes)
			(layer "F.Fab")
			(hide yes)
			(effects
				(font
					(size 0.7874 0.5842)
					(thickness 0.1524)
				)
			)
		)
		(duplicate_pad_numbers_are_jumpers no)
		(fp_line
			(start -1.143 0.5588)
			(end 1.143 0.5588)
			(stroke
				(width 0.1)
				(type default)
			)
			(layer "F.SilkS")
		)
		(fp_line
			(start 1.143 0.5588)
			(end 1.143 -0.5588)
			(stroke
				(width 0.1)
				(type default)
			)
			(layer "F.SilkS")
		)
		(fp_line
			(start -1.143 -0.5588)
			(end -1.143 0.5588)
			(stroke
				(width 0.1)
				(type default)
			)
			(layer "F.SilkS")
		)
		(fp_line
			(start 1.143 -0.5588)
			(end -1.143 -0.5588)
			(stroke
				(width 0.1)
				(type default)
			)
			(layer "F.SilkS")
		)
		(fp_poly
			(pts
				(xy -1.143 0.5588) (xy 1.143 0.5588) (xy 1.143 -0.5588) (xy -1.143 -0.5588)
			)
			(stroke
				(width 0)
				(type default)
			)
			(fill no)
			(layer "F.CrtYd")
		)
		(fp_line
			(start -0.508 0.3048)
			(end 0.508 0.3048)
			(stroke
				(width 0.1)
				(type default)
			)
			(layer "F.Fab")
		)
		(fp_line
			(start 0.508 0.3048)
			(end 0.508 -0.3048)
			(stroke
				(width 0.1)
				(type default)
			)
			(layer "F.Fab")
		)
		(fp_line
			(start -0.508 -0.3048)
			(end -0.508 0.3048)
			(stroke
				(width 0.1)
				(type default)
			)
			(layer "F.Fab")
		)
		(fp_line
			(start 0.508 -0.3048)
			(end -0.508 -0.3048)
			(stroke
				(width 0.1)
				(type default)
			)
			(layer "F.Fab")
		)
		(pad "1" smd rect
			(at -0.5334 0 270)
			(size 0.7112 0.6096)
			(layers "F.Cu" "F.Mask" "F.Paste")
			(net "SG")
		)
		(pad "2" smd rect
			(at 0.5334 0 270)
			(size 0.7112 0.6096)
			(layers "F.Cu" "F.Mask" "F.Paste")
			(net "BF_SMA1_SIG_IO_CONN")
		)
		(zone
			(layer "F.Cu")
			(hatch none 0.5)
			(connect_pads
				(clearance 0)
			)
			(min_thickness 0.25)
			(keepout
				(tracks allowed)
				(vias not_allowed)
				(pads allowed)
				(copperpour not_allowed)
				(footprints allowed)
			)
			(placement
				(enabled no)
				(sheetname "")
			)
			(fill
				(thermal_gap 0.5)
				(thermal_bridge_width 0.5)
				(island_removal_mode 0)
			)
			(polygon
				(pts
					(xy 11.176 -59.69) (xy 11.176 -59.5376) (xy 11.7856 -59.5376) (xy 11.7856 -59.69)
				)
			)
		)
		(zone
			(layer "F.Cu")
			(hatch none 0.5)
			(connect_pads
				(clearance 0)
			)
			(min_thickness 0.25)
			(keepout
				(tracks not_allowed)
				(vias allowed)
				(pads allowed)
				(copperpour not_allowed)
				(footprints allowed)
			)
			(placement
				(enabled no)
				(sheetname "")
			)
			(fill
				(thermal_gap 0.5)
				(thermal_bridge_width 0.5)
				(island_removal_mode 0)
			)
			(polygon
				(pts
					(xy 11.176 -59.69) (xy 11.176 -59.5376) (xy 11.7856 -59.5376) (xy 11.7856 -59.69)
				)
			)
		)
	)
)
